# T6G (Grand Teton) — schematic netlist excerpt (pin names and nets, part order shuffled) for the footprints in the layout excerpt that follows; sources: Cadence DE-HDL packaged netlist, KiCad conversion of 04192023_DAF0TMB3IC0_F0TG_MB_C_brd_V02_OCP.brd

R1286  Q_RES  4.7K 5% CHIP  pkg 0402LF  page 83 : A = FM_P1_PCC1_N ; B = PVDD18_S5_P1
PC399  Q_CAP  2.2UF 10V 10% X6S  pkg C0402  page 219 : A = PVDDCR_CPU1_P1_VCC4 ; B = GND
C1570  Q_CAP_DIFFBUS  DIFF BUS_0.22UF 6.3V 20% X6S  pkg C0201  page 65 : \1\ = P5E_CPU0_G3_TX_C_DN<4> ; \2\ = P5E_CPU0_G3_TX_DN<4>

(kicad_pcb
	(version 20260206)
	(generator "pcbnew")
	(generator_version "10.0")
	(general
		(thickness 1.6)
		(legacy_teardrops no)
	)
	(paper "A4")
	(title_block
		(title "04192023_DAF0TMB3IC0_F0TG_MB_C_brd_V02_OCP.brd")
		(comment 1 "Grand Teton / footprints 2372-2374 of 8354")
	)
	(layers
		(0 "F.Cu" signal "TOP")
		(4 "In1.Cu" signal "GND")
		(6 "In2.Cu" signal "IN1")
		(8 "In3.Cu" signal "GND1")
		(10 "In4.Cu" signal "IN2")
		(12 "In5.Cu" signal "GND2")
		(14 "In6.Cu" signal "IN3")
		(16 "In7.Cu" signal "GND3")
		(18 "In8.Cu" signal "VCC")
		(20 "In9.Cu" signal "VCC1")
		(22 "In10.Cu" signal "GND4")
		(24 "In11.Cu" signal "IN4")
		(26 "In12.Cu" signal "GND5")
		(28 "In13.Cu" signal "IN5")
		(30 "In14.Cu" signal "GND6")
		(32 "In15.Cu" signal "IN6")
		(34 "In16.Cu" signal "GND7")
		(2 "B.Cu" signal "BOTTOM")
		(9 "F.Adhes" user "F.Adhesive")
		(11 "B.Adhes" user "B.Adhesive")
		(13 "F.Paste" user "Package Geometry/Pastemask Top")
		(15 "B.Paste" user "Package Geometry/Pastemask Bottom")
		(5 "F.SilkS" user "Ref Des/Silkscreen Top")
		(7 "B.SilkS" user "Ref Des/Silkscreen Bottom")
		(1 "F.Mask" user "Board Geometry/Soldermask Top")
		(3 "B.Mask" user "Board Geometry/Soldermask Bottom")
		(17 "Dwgs.User" user "User.Drawings")
		(19 "Cmts.User" user "User.Comments")
		(21 "Eco1.User" user "User.Eco1")
		(23 "Eco2.User" user "User.Eco2")
		(25 "Edge.Cuts" user "Board Geometry/Outline")
		(27 "Margin" user)
		(31 "F.CrtYd" user "Package Geometry/Place Bound Top")
		(29 "B.CrtYd" user "Package Geometry/Place Bound Bottom")
		(35 "F.Fab" user "Ref Des/Assembly Top")
		(33 "B.Fab" user "Ref Des/Assembly Bottom")
	)
	(footprint ""
		(layer "F.Cu")
		(at 183.007 -137.632948 90)
		(property "Reference" "R1286"
			(at 0 0 90)
			(layer "F.SilkS")
			(hide yes)
			(effects
				(font
					(size 1.27 1.27)
				)
			)
		)
		(property "Value" ""
			(at 0 0 90)
			(layer "F.Fab")
			(effects
				(font
					(size 1.27 1.27)
				)
			)
		)
		(duplicate_pad_numbers_are_jumpers no)
		(fp_line
			(start 0.7874 -0.4064)
			(end 0.7874 0.4064)
			(stroke
				(width 0.1524)
				(type default)
			)
			(layer "F.SilkS")
		)
		(fp_line
			(start -0.7874 -0.4064)
			(end 0.7874 -0.4064)
			(stroke
				(width 0.1524)
				(type default)
			)
			(layer "F.SilkS")
		)
		(fp_line
			(start 0.7874 0.4064)
			(end -0.7874 0.4064)
			(stroke
				(width 0.1524)
				(type default)
			)
			(layer "F.SilkS")
		)
		(fp_line
			(start -0.7874 0.4064)
			(end -0.7874 -0.4064)
			(stroke
				(width 0.1524)
				(type default)
			)
			(layer "F.SilkS")
		)
		(fp_line
			(start -0.12065 -0.305054)
			(end -0.12065 -0.2794)
			(stroke
				(width 0.1)
				(type default)
			)
			(layer "F.Fab")
		)
		(fp_line
			(start -0.67945 -0.305054)
			(end -0.12065 -0.305054)
			(stroke
				(width 0.1)
				(type default)
			)
			(layer "F.Fab")
		)
		(fp_line
			(start 0.67945 -0.3048)
			(end 0.67945 0.3048)
			(stroke
				(width 0.1)
				(type default)
			)
			(layer "F.Fab")
		)
		(fp_line
			(start 0.12065 -0.3048)
			(end 0.67945 -0.3048)
			(stroke
				(width 0.1)
				(type default)
			)
			(layer "F.Fab")
		)
		(fp_line
			(start 0.12065 -0.2794)
			(end 0.12065 -0.3048)
			(stroke
				(width 0.1)
				(type default)
			)
			(layer "F.Fab")
		)
		(fp_line
			(start -0.12065 -0.2794)
			(end 0.12065 -0.2794)
			(stroke
				(width 0.1)
				(type default)
			)
			(layer "F.Fab")
		)
		(fp_line
			(start 0.120396 0.2794)
			(end -0.12065 0.2794)
			(stroke
				(width 0.1)
				(type default)
			)
			(layer "F.Fab")
		)
		(fp_line
			(start -0.12065 0.2794)
			(end -0.12065 0.3048)
			(stroke
				(width 0.1)
				(type default)
			)
			(layer "F.Fab")
		)
		(fp_line
			(start 0.67945 0.3048)
			(end 0.120396 0.3048)
			(stroke
				(width 0.1)
				(type default)
			)
			(layer "F.Fab")
		)
		(fp_line
			(start 0.120396 0.3048)
			(end 0.120396 0.2794)
			(stroke
				(width 0.1)
				(type default)
			)
			(layer "F.Fab")
		)
		(fp_line
			(start -0.12065 0.3048)
			(end -0.67945 0.3048)
			(stroke
				(width 0.1)
				(type default)
			)
			(layer "F.Fab")
		)
		(fp_line
			(start -0.67945 0.3048)
			(end -0.67945 -0.305054)
			(stroke
				(width 0.1)
				(type default)
			)
			(layer "F.Fab")
		)
		(pad "1" smd circle
			(at -0.40005 0 90)
			(size 0 0)
			(layers "F.Cu" "F.Mask" "F.Paste")
			(net "FM_P1_PCC1_N")
		)
		(pad "2" smd circle
			(at 0.40005 0 90)
			(size 0 0)
			(layers "F.Cu" "F.Mask" "F.Paste")
			(net "PVDD18_S5_P1")
		)
	)
	(footprint ""
		(layer "F.Cu")
		(at 421.047164 -17.624298 90)
		(property "Reference" "C1570"
			(at 0 0 90)
			(layer "F.SilkS")
			(hide yes)
			(effects
				(font
					(size 1.27 1.27)
				)
			)
		)
		(property "Value" ""
			(at 0 0 90)
			(layer "F.Fab")
			(effects
				(font
					(size 1.27 1.27)
				)
			)
		)
		(duplicate_pad_numbers_are_jumpers no)
		(fp_line
			(start 0.299974 -0.150114)
			(end 0.299974 0.150114)
			(stroke
				(width 0.1)
				(type default)
			)
			(layer "F.Fab")
		)
		(fp_line
			(start -0.299974 -0.150114)
			(end 0.299974 -0.150114)
			(stroke
				(width 0.1)
				(type default)
			)
			(layer "F.Fab")
		)
		(fp_line
			(start 0.299974 0.150114)
			(end -0.299974 0.150114)
			(stroke
				(width 0.1)
				(type default)
			)
			(layer "F.Fab")
		)
		(fp_line
			(start -0.299974 0.150114)
			(end -0.299974 -0.150114)
			(stroke
				(width 0.1)
				(type default)
			)
			(layer "F.Fab")
		)
		(pad "1" smd rect
			(at -0.2667 0 90)
			(size 0.3048 0.381)
			(layers "F.Cu" "F.Mask" "F.Paste")
			(net "P5E_CPU0_G3_TX_C_DN<4>")
		)
		(pad "2" smd rect
			(at 0.2667 0 90)
			(size 0.3048 0.381)
			(layers "F.Cu" "F.Mask" "F.Paste")
			(net "P5E_CPU0_G3_TX_DN<4>")
		)
	)
	(footprint ""
		(layer "F.Cu")
		(at 58.191654 -349.386398 90)
		(property "Reference" "PC399"
			(at 0 0 90)
			(layer "F.SilkS")
			(hide yes)
			(effects
				(font
					(size 1.27 1.27)
				)
			)
		)
		(property "Value" ""
			(at 0 0 90)
			(layer "F.Fab")
			(effects
				(font
					(size 1.27 1.27)
				)
			)
		)
		(duplicate_pad_numbers_are_jumpers no)
		(fp_line
			(start 0.7874 -0.4064)
			(end 0.7874 0.4064)
			(stroke
				(width 0.1524)
				(type default)
			)
			(layer "F.SilkS")
		)
		(fp_line
			(start -0.7874 -0.4064)
			(end 0.7874 -0.4064)
			(stroke
				(width 0.1524)
				(type default)
			)
			(layer "F.SilkS")
		)
		(fp_line
			(start 0.7874 0.4064)
			(end 0.397002 0.4064)
			(stroke
				(width 0.1524)
				(type default)
			)
			(layer "F.SilkS")
		)
		(fp_line
			(start -0.212598 0.4064)
			(end -0.7874 0.4064)
			(stroke
				(width 0.1524)
				(type default)
			)
			(layer "F.SilkS")
		)
		(fp_line
			(start -0.7874 0.4064)
			(end -0.7874 -0.4064)
			(stroke
				(width 0.1524)
				(type default)
			)
			(layer "F.SilkS")
		)
		(fp_line
			(start -0.12065 -0.305054)
			(end -0.12065 -0.2794)
			(stroke
				(width 0.1)
				(type default)
			)
			(layer "F.Fab")
		)
		(fp_line
			(start -0.67945 -0.305054)
			(end -0.12065 -0.305054)
			(stroke
				(width 0.1)
				(type default)
			)
			(layer "F.Fab")
		)
		(fp_line
			(start 0.67945 -0.3048)
			(end 0.67945 0.3048)
			(stroke
				(width 0.1)
				(type default)
			)
			(layer "F.Fab")
		)
		(fp_line
			(start 0.12065 -0.3048)
			(end 0.67945 -0.3048)
			(stroke
				(width 0.1)
				(type default)
			)
			(layer "F.Fab")
		)
		(fp_line
			(start 0.12065 -0.2794)
			(end 0.12065 -0.3048)
			(stroke
				(width 0.1)
				(type default)
			)
			(layer "F.Fab")
		)
		(fp_line
			(start -0.12065 -0.2794)
			(end 0.12065 -0.2794)
			(stroke
				(width 0.1)
				(type default)
			)
			(layer "F.Fab")
		)
		(fp_line
			(start 0.120396 0.2794)
			(end -0.12065 0.2794)
			(stroke
				(width 0.1)
				(type default)
			)
			(layer "F.Fab")
		)
		(fp_line
			(start -0.12065 0.2794)
			(end -0.12065 0.3048)
			(stroke
				(width 0.1)
				(type default)
			)
			(layer "F.Fab")
		)
		(fp_line
			(start 0.67945 0.3048)
			(end 0.120396 0.3048)
			(stroke
				(width 0.1)
				(type default)
			)
			(layer "F.Fab")
		)
		(fp_line
			(start 0.120396 0.3048)
			(end 0.120396 0.2794)
			(stroke
				(width 0.1)
				(type default)
			)
			(layer "F.Fab")
		)
		(fp_line
			(start -0.12065 0.3048)
			(end -0.67945 0.3048)
			(stroke
				(width 0.1)
				(type default)
			)
			(layer "F.Fab")
		)
		(fp_line
			(start -0.67945 0.3048)
			(end -0.67945 -0.305054)
			(stroke
				(width 0.1)
				(type default)
			)
			(layer "F.Fab")
		)
		(pad "1" smd circle
			(at -0.40005 0 90)
			(size 0 0)
			(layers "F.Cu" "F.Mask" "F.Paste")
			(net "PVDDCR_CPU1_P1_VCC4")
		)
		(pad "2" smd circle
			(at 0.40005 0 90)
			(size 0 0)
			(layers "F.Cu" "F.Mask" "F.Paste")
			(net "GND")
		)
	)
)
